# S9S_MB_2U (Grand Teton) — schematic netlist excerpt (pin names and nets, part order shuffled) for the footprints in the layout excerpt that follows; sources: Cadence DE-HDL packaged netlist, KiCad conversion of 03242023_DA0F0TMBIJ0_F0T_Motherboard_J_brd_V01_OCP.brd

R3958  Q_RES  0 5% EMPTY  pkg 0402LF  page 192 : A = P12V_E1S_UV_0_R ; B = P12V_E1S_UV_0

U28  PCA9617ADP  IC  pkg TSSOP8_3XB  page 235
  VCCA  = PVNN_TERM_CPU0
  SCLA  = SMB_PEHPCPU0_GTL_R_SCL
  SDAA  = SMB_PEHPCPU0_GTL_R_SDA
  GND  = GND
  EN  = TP_SMB_PEHPCPU0_EN
  SDAB  = SMB_PEHPCPU0_LVC3_SDA_R0
  SCLB  = SMB_PEHPCPU0_LVC3_SCL_R0
  VCCB  = P3V3_AUX

(kicad_pcb
	(version 20260206)
	(generator "pcbnew")
	(generator_version "10.0")
	(general
		(thickness 1.6)
		(legacy_teardrops no)
	)
	(paper "A4")
	(title_block
		(title "03242023_DA0F0TMBIJ0_F0T_Motherboard_J_brd_V01_OCP.brd")
		(comment 1 "Grand Teton / footprints 5435-5436 of 6105")
	)
	(layers
		(0 "F.Cu" signal "TOP")
		(4 "In1.Cu" signal "GND")
		(6 "In2.Cu" signal "IN1")
		(8 "In3.Cu" signal "GND1")
		(10 "In4.Cu" signal "IN2")
		(12 "In5.Cu" signal "GND2")
		(14 "In6.Cu" signal "IN3")
		(16 "In7.Cu" signal "GND3")
		(18 "In8.Cu" signal "VCC")
		(20 "In9.Cu" signal "VCC1")
		(22 "In10.Cu" signal "GND4")
		(24 "In11.Cu" signal "IN4")
		(26 "In12.Cu" signal "GND5")
		(28 "In13.Cu" signal "IN5")
		(30 "In14.Cu" signal "GND6")
		(32 "In15.Cu" signal "IN6")
		(34 "In16.Cu" signal "GND7")
		(2 "B.Cu" signal "BOTTOM")
		(9 "F.Adhes" user "F.Adhesive")
		(11 "B.Adhes" user "B.Adhesive")
		(13 "F.Paste" user "Package Geometry/Pastemask Top")
		(15 "B.Paste" user "Package Geometry/Pastemask Bottom")
		(5 "F.SilkS" user "Ref Des/Silkscreen Top")
		(7 "B.SilkS" user "Ref Des/Silkscreen Bottom")
		(1 "F.Mask" user "Board Geometry/Soldermask Top")
		(3 "B.Mask" user "Board Geometry/Soldermask Bottom")
		(17 "Dwgs.User" user "User.Drawings")
		(19 "Cmts.User" user "User.Comments")
		(21 "Eco1.User" user "User.Eco1")
		(23 "Eco2.User" user "User.Eco2")
		(25 "Edge.Cuts" user "Board Geometry/Outline")
		(27 "Margin" user)
		(31 "F.CrtYd" user "Package Geometry/Place Bound Top")
		(29 "B.CrtYd" user "Package Geometry/Place Bound Bottom")
		(35 "F.Fab" user "Ref Des/Assembly Top")
		(33 "B.Fab" user "Ref Des/Assembly Bottom")
	)
	(footprint ""
		(layer "B.Cu")
		(at 250.30303 -44.979082 90)
		(property "Reference" "R3958"
			(at 0 0 90)
			(layer "B.SilkS")
			(hide yes)
			(effects
				(font
					(size 1.27 1.27)
				)
				(justify mirror)
			)
		)
		(property "Value" ""
			(at 0 0 90)
			(layer "B.Fab")
			(effects
				(font
					(size 1.27 1.27)
				)
				(justify mirror)
			)
		)
		(duplicate_pad_numbers_are_jumpers no)
		(fp_line
			(start 0.7874 -0.4064)
			(end -0.7874 -0.4064)
			(stroke
				(width 0.1524)
				(type default)
			)
			(layer "B.SilkS")
		)
		(fp_line
			(start -0.7874 -0.4064)
			(end -0.7874 0.4064)
			(stroke
				(width 0.1524)
				(type default)
			)
			(layer "B.SilkS")
		)
		(fp_line
			(start 0.7874 0.4064)
			(end 0.7874 -0.4064)
			(stroke
				(width 0.1524)
				(type default)
			)
			(layer "B.SilkS")
		)
		(fp_line
			(start -0.7874 0.4064)
			(end 0.7874 0.4064)
			(stroke
				(width 0.1524)
				(type default)
			)
			(layer "B.SilkS")
		)
		(fp_line
			(start 0.67945 -0.305054)
			(end 0.12065 -0.305054)
			(stroke
				(width 0.1)
				(type default)
			)
			(layer "B.Fab")
		)
		(fp_line
			(start 0.12065 -0.305054)
			(end 0.12065 -0.2794)
			(stroke
				(width 0.1)
				(type default)
			)
			(layer "B.Fab")
		)
		(fp_line
			(start -0.12065 -0.3048)
			(end -0.67945 -0.3048)
			(stroke
				(width 0.1)
				(type default)
			)
			(layer "B.Fab")
		)
		(fp_line
			(start -0.67945 -0.3048)
			(end -0.67945 0.3048)
			(stroke
				(width 0.1)
				(type default)
			)
			(layer "B.Fab")
		)
		(fp_line
			(start 0.12065 -0.2794)
			(end -0.12065 -0.2794)
			(stroke
				(width 0.1)
				(type default)
			)
			(layer "B.Fab")
		)
		(fp_line
			(start -0.12065 -0.2794)
			(end -0.12065 -0.3048)
			(stroke
				(width 0.1)
				(type default)
			)
			(layer "B.Fab")
		)
		(fp_line
			(start 0.12065 0.2794)
			(end 0.12065 0.3048)
			(stroke
				(width 0.1)
				(type default)
			)
			(layer "B.Fab")
		)
		(fp_line
			(start -0.120396 0.2794)
			(end 0.12065 0.2794)
			(stroke
				(width 0.1)
				(type default)
			)
			(layer "B.Fab")
		)
		(fp_line
			(start 0.67945 0.3048)
			(end 0.67945 -0.305054)
			(stroke
				(width 0.1)
				(type default)
			)
			(layer "B.Fab")
		)
		(fp_line
			(start 0.12065 0.3048)
			(end 0.67945 0.3048)
			(stroke
				(width 0.1)
				(type default)
			)
			(layer "B.Fab")
		)
		(fp_line
			(start -0.120396 0.3048)
			(end -0.120396 0.2794)
			(stroke
				(width 0.1)
				(type default)
			)
			(layer "B.Fab")
		)
		(fp_line
			(start -0.67945 0.3048)
			(end -0.120396 0.3048)
			(stroke
				(width 0.1)
				(type default)
			)
			(layer "B.Fab")
		)
		(pad "1" smd circle
			(at 0.40005 0 270)
			(size 0 0)
			(layers "B.Cu" "B.Mask" "B.Paste")
			(net "P12V_E1S_UV_0_R")
		)
		(pad "2" smd circle
			(at -0.40005 0 270)
			(size 0 0)
			(layers "B.Cu" "B.Mask" "B.Paste")
			(net "P12V_E1S_UV_0")
		)
	)
	(footprint ""
		(layer "B.Cu")
		(at 369.477036 -187.181744)
		(property "Reference" "U28"
			(at -0.760476 -4.318254 0)
			(unlocked yes)
			(layer "B.SilkS")
			(effects
				(font
					(size 0.7874 0.5842)
					(thickness 0.1524)
				)
				(justify left mirror)
			)
		)
		(property "Value" ""
			(at 0 0 0)
			(layer "B.Fab")
			(effects
				(font
					(size 1.27 1.27)
				)
				(justify mirror)
			)
		)
		(duplicate_pad_numbers_are_jumpers no)
		(fp_line
			(start -1.463548 -1.549908)
			(end -1.463548 1.549908)
			(stroke
				(width 0.1524)
				(type default)
			)
			(layer "B.SilkS")
		)
		(fp_line
			(start -1.463548 1.549908)
			(end 1.463548 1.549908)
			(stroke
				(width 0.1524)
				(type default)
			)
			(layer "B.SilkS")
		)
		(fp_line
			(start -0.762 -1.549908)
			(end -1.463548 -1.549908)
			(stroke
				(width 0.1524)
				(type default)
			)
			(layer "B.SilkS")
		)
		(fp_line
			(start 0 -0.762)
			(end -0.762 -1.549908)
			(stroke
				(width 0.1524)
				(type default)
			)
			(layer "B.SilkS")
		)
		(fp_line
			(start 0.787908 -1.549908)
			(end 0 -0.762)
			(stroke
				(width 0.1524)
				(type default)
			)
			(layer "B.SilkS")
		)
		(fp_line
			(start 1.463548 -1.549908)
			(end 0.787908 -1.549908)
			(stroke
				(width 0.1524)
				(type default)
			)
			(layer "B.SilkS")
		)
		(fp_line
			(start 1.463548 1.549908)
			(end 1.463548 -1.549908)
			(stroke
				(width 0.1524)
				(type default)
			)
			(layer "B.SilkS")
		)
		(fp_poly
			(pts
				(xy 2.848356 -2.227326) (xy 3.360674 -1.878584) (xy 2.7559 -1.54051)
			)
			(stroke
				(width 0)
				(type default)
			)
			(fill yes)
			(layer "B.SilkS")
		)
		(fp_line
			(start -1.549908 -1.549908)
			(end -1.549908 1.549908)
			(stroke
				(width 0.1)
				(type default)
			)
			(layer "B.Fab")
		)
		(fp_line
			(start -1.549908 1.549908)
			(end 1.549908 1.549908)
			(stroke
				(width 0.1)
				(type default)
			)
			(layer "B.Fab")
		)
		(fp_line
			(start 1.549908 -1.549908)
			(end -1.549908 -1.549908)
			(stroke
				(width 0.1)
				(type default)
			)
			(layer "B.Fab")
		)
		(fp_line
			(start 1.549908 1.549908)
			(end 1.549908 -1.549908)
			(stroke
				(width 0.1)
				(type default)
			)
			(layer "B.Fab")
		)
		(fp_poly
			(pts
				(xy 3.4798 -1.359916) (xy 2.86004 -1.050036) (xy 3.4798 -0.740156)
			)
			(stroke
				(width 0)
				(type default)
			)
			(fill yes)
			(layer "B.Fab")
		)
		(pad "1" smd rect
			(at 2.175002 -1.050036 90)
			(size 0.6096 1.1684)
			(layers "B.Cu" "B.Mask" "B.Paste")
			(net "PVNN_TERM_CPU0")
		)
		(pad "2" smd rect
			(at 2.175002 -0.32512 90)
			(size 0.4318 1.1684)
			(layers "B.Cu" "B.Mask" "B.Paste")
			(net "SMB_PEHPCPU0_GTL_R_SCL")
		)
		(pad "3" smd rect
			(at 2.175002 0.32512 90)
			(size 0.4318 1.1684)
			(layers "B.Cu" "B.Mask" "B.Paste")
			(net "SMB_PEHPCPU0_GTL_R_SDA")
		)
		(pad "4" smd rect
			(at 2.175002 1.050036 90)
			(size 0.6096 1.1684)
			(layers "B.Cu" "B.Mask" "B.Paste")
			(net "GND")
		)
		(pad "5" smd rect
			(at -2.175002 1.050036 90)
			(size 0.6096 1.1684)
			(layers "B.Cu" "B.Mask" "B.Paste")
			(net "TP_SMB_PEHPCPU0_EN")
		)
		(pad "6" smd rect
			(at -2.175002 0.32512 90)
			(size 0.4318 1.1684)
			(layers "B.Cu" "B.Mask" "B.Paste")
			(net "SMB_PEHPCPU0_LVC3_SDA_R0")
		)
		(pad "7" smd rect
			(at -2.175002 -0.32512 90)
			(size 0.4318 1.1684)
			(layers "B.Cu" "B.Mask" "B.Paste")
			(net "SMB_PEHPCPU0_LVC3_SCL_R0")
		)
		(pad "8" smd rect
			(at -2.175002 -1.050036 90)
			(size 0.6096 1.1684)
			(layers "B.Cu" "B.Mask" "B.Paste")
			(net "P3V3_AUX")
		)
	)
)
